(kicad_pcb
	(version 20260206)
	(generator "pcbnew")
	(generator_version "10.0")
	(general
		(thickness 1.6)
		(legacy_teardrops no)
	)
	(paper "A4")
	(title_block
		(title "03242023_DA0F0TMBIJ0_F0T_Motherboard_J_brd_V01_OCP.brd")
		(comment 1 "Grand Teton / footprints 3221-3225 of 6105")
	)
	(layers
		(0 "F.Cu" signal "TOP")
		(4 "In1.Cu" signal "GND")
		(6 "In2.Cu" signal "IN1")
		(8 "In3.Cu" signal "GND1")
		(10 "In4.Cu" signal "IN2")
		(12 "In5.Cu" signal "GND2")
		(14 "In6.Cu" signal "IN3")
		(16 "In7.Cu" signal "GND3")
		(18 "In8.Cu" signal "VCC")
		(20 "In9.Cu" signal "VCC1")
		(22 "In10.Cu" signal "GND4")
		(24 "In11.Cu" signal "IN4")
		(26 "In12.Cu" signal "GND5")
		(28 "In13.Cu" signal "IN5")
		(30 "In14.Cu" signal "GND6")
		(32 "In15.Cu" signal "IN6")
		(34 "In16.Cu" signal "GND7")
		(2 "B.Cu" signal "BOTTOM")
		(9 "F.Adhes" user "F.Adhesive")
		(11 "B.Adhes" user "B.Adhesive")
		(13 "F.Paste" user "Package Geometry/Pastemask Top")
		(15 "B.Paste" user "Package Geometry/Pastemask Bottom")
		(5 "F.SilkS" user "Ref Des/Silkscreen Top")
		(7 "B.SilkS" user "Ref Des/Silkscreen Bottom")
		(1 "F.Mask" user "Board Geometry/Soldermask Top")
		(3 "B.Mask" user "Board Geometry/Soldermask Bottom")
		(17 "Dwgs.User" user "User.Drawings")
		(19 "Cmts.User" user "User.Comments")
		(21 "Eco1.User" user "User.Eco1")
		(23 "Eco2.User" user "User.Eco2")
		(25 "Edge.Cuts" user "Board Geometry/Outline")
		(27 "Margin" user)
		(31 "F.CrtYd" user "Package Geometry/Place Bound Top")
		(29 "B.CrtYd" user "Package Geometry/Place Bound Bottom")
		(35 "F.Fab" user "Ref Des/Assembly Top")
		(33 "B.Fab" user "Ref Des/Assembly Bottom")
	)
	(footprint ""
		(layer "F.Cu")
		(at 479.84537 -121.640092 -90)
		(property "Reference" "X36"
			(at 2.387092 -2.4003 90)
			(unlocked yes)
			(layer "F.SilkS")
			(effects
				(font
					(size 0.7874 0.5842)
					(thickness 0.1524)
				)
				(justify left)
			)
		)
		(property "Value" ""
			(at 0 0 270)
			(layer "F.Fab")
			(effects
				(font
					(size 1.27 1.27)
				)
			)
		)
		(property "Device Type" "TP_TDR_4P_FTS_TH-TP_TDR_4P_DIPA"
			(at 1.30175 1.27 0)
			(unlocked yes)
			(layer "F.Fab")
			(hide yes)
			(effects
				(font
					(size 0.635 0.4064)
					(thickness 0.1524)
				)
			)
		)
		(property "User Part Number" "N_A"
			(at 1.30175 1.27 0)
			(unlocked yes)
			(layer "Cmts.User")
			(hide yes)
			(effects
				(font
					(size 0.635 0.4064)
					(thickness 0.1524)
				)
			)
		)
		(duplicate_pad_numbers_are_jumpers no)
		(fp_line
			(start 0 3.81)
			(end 2.54 3.81)
			(stroke
				(width 0.1524)
				(type default)
			)
			(layer "F.SilkS")
		)
		(fp_line
			(start 2.54 3.81)
			(end 2.54 3.6703)
			(stroke
				(width 0.1524)
				(type default)
			)
			(layer "F.SilkS")
		)
		(fp_line
			(start 0 3.175)
			(end 0 3.81)
			(stroke
				(width 0.1524)
				(type default)
			)
			(layer "F.SilkS")
		)
		(fp_line
			(start 2.54 1.4097)
			(end 2.54 1.1303)
			(stroke
				(width 0.1524)
				(type default)
			)
			(layer "F.SilkS")
		)
		(fp_line
			(start 0 0.635)
			(end 0 1.905)
			(stroke
				(width 0.1524)
				(type default)
			)
			(layer "F.SilkS")
		)
		(fp_line
			(start 2.54 -1.1303)
			(end 2.54 -1.27)
			(stroke
				(width 0.1524)
				(type default)
			)
			(layer "F.SilkS")
		)
		(fp_line
			(start 0 -1.27)
			(end 0 -0.635)
			(stroke
				(width 0.1524)
				(type default)
			)
			(layer "F.SilkS")
		)
		(fp_line
			(start 2.54 -1.27)
			(end 0 -1.27)
			(stroke
				(width 0.1524)
				(type default)
			)
			(layer "F.SilkS")
		)
		(fp_poly
			(pts
				(xy -0.761746 0) (xy -2.285746 -0.762) (xy -2.285746 0.762)
			)
			(stroke
				(width 0)
				(type default)
			)
			(fill yes)
			(layer "F.SilkS")
		)
		(fp_line
			(start 0 3.81)
			(end 2.54 3.81)
			(stroke
				(width 0.1)
				(type default)
			)
			(layer "F.Fab")
		)
		(fp_line
			(start 2.54 3.81)
			(end 2.54 -1.27)
			(stroke
				(width 0.1)
				(type default)
			)
			(layer "F.Fab")
		)
		(fp_line
			(start 0 -1.27)
			(end 0 3.81)
			(stroke
				(width 0.1)
				(type default)
			)
			(layer "F.Fab")
		)
		(fp_line
			(start 2.54 -1.27)
			(end 0 -1.27)
			(stroke
				(width 0.1)
				(type default)
			)
			(layer "F.Fab")
		)
		(fp_poly
			(pts
				(xy -0.761746 0) (xy -2.285746 -0.762) (xy -2.285746 0.762)
			)
			(stroke
				(width 0)
				(type default)
			)
			(fill yes)
			(layer "F.Fab")
		)
		(pad "1" thru_hole circle
			(at 0 0 270)
			(size 1.0033 1.0033)
			(drill 0.249936)
			(layers "*.Cu" "*.Mask")
			(remove_unused_layers no)
			(net "TDR_DIFF_85_NECK_IN3_DP")
			(clearance 0.10795)
			(thermal_gap 0.10795)
			(padstack
				(mode front_inner_back)
				(layer "Inner"
					(shape circle)
					(size 0.8001 0.8001)
					(clearance 0.1524)
				)
				(layer "B.Cu"
					(shape circle)
					(size 1.0033 1.0033)
					(clearance 0.10795)
				)
			)
		)
		(pad "2" thru_hole circle
			(at 2.54 0 270)
			(size 1.9939 1.9939)
			(drill 0.249936)
			(layers "*.Cu" "*.Mask")
			(remove_unused_layers no)
			(net "T1_GND")
			(clearance 0.10795)
			(thermal_gap 0.10795)
			(padstack
				(mode front_inner_back)
				(layer "Inner"
					(shape circle)
					(size 0.8001 0.8001)
					(clearance 0.1524)
				)
				(layer "B.Cu"
					(shape circle)
					(size 1.9939 1.9939)
					(clearance 0.10795)
				)
			)
		)
		(pad "3" thru_hole circle
			(at 2.54 2.54 270)
			(size 1.9939 1.9939)
			(drill 0.249936)
			(layers "*.Cu" "*.Mask")
			(remove_unused_layers no)
			(net "T1_GND")
			(clearance 0.10795)
			(thermal_gap 0.10795)
			(padstack
				(mode front_inner_back)
				(layer "Inner"
					(shape circle)
					(size 0.8001 0.8001)
					(clearance 0.1524)
				)
				(layer "B.Cu"
					(shape circle)
					(size 1.9939 1.9939)
					(clearance 0.10795)
				)
			)
		)
		(pad "4" thru_hole circle
			(at 0 2.54 270)
			(size 1.0033 1.0033)
			(drill 0.249936)
			(layers "*.Cu" "*.Mask")
			(remove_unused_layers no)
			(net "TDR_DIFF_85_NECK_IN3_DN")
			(clearance 0.10795)
			(thermal_gap 0.10795)
			(padstack
				(mode front_inner_back)
				(layer "Inner"
					(shape circle)
					(size 0.8001 0.8001)
					(clearance 0.1524)
				)
				(layer "B.Cu"
					(shape circle)
					(size 1.0033 1.0033)
					(clearance 0.10795)
				)
			)
		)
	)
	(footprint ""
		(layer "F.Cu")
		(at 174.1424 -93.538548 90)
		(property "Reference" "R4597"
			(at 0 0 90)
			(layer "F.SilkS")
			(hide yes)
			(effects
				(font
					(size 1.27 1.27)
				)
			)
		)
		(property "Value" ""
			(at 0 0 90)
			(layer "F.Fab")
			(effects
				(font
					(size 1.27 1.27)
				)
			)
		)
		(duplicate_pad_numbers_are_jumpers no)
		(fp_line
			(start 0.7874 -0.4064)
			(end 0.7874 0.4064)
			(stroke
				(width 0.1524)
				(type default)
			)
			(layer "F.SilkS")
		)
		(fp_line
			(start -0.7874 -0.4064)
			(end 0.7874 -0.4064)
			(stroke
				(width 0.1524)
				(type default)
			)
			(layer "F.SilkS")
		)
		(fp_line
			(start 0.7874 0.4064)
			(end -0.7874 0.4064)
			(stroke
				(width 0.1524)
				(type default)
			)
			(layer "F.SilkS")
		)
		(fp_line
			(start -0.7874 0.4064)
			(end -0.7874 -0.4064)
			(stroke
				(width 0.1524)
				(type default)
			)
			(layer "F.SilkS")
		)
		(fp_line
			(start -0.12065 -0.305054)
			(end -0.12065 -0.2794)
			(stroke
				(width 0.1)
				(type default)
			)
			(layer "F.Fab")
		)
		(fp_line
			(start -0.67945 -0.305054)
			(end -0.12065 -0.305054)
			(stroke
				(width 0.1)
				(type default)
			)
			(layer "F.Fab")
		)
		(fp_line
			(start 0.67945 -0.3048)
			(end 0.67945 0.3048)
			(stroke
				(width 0.1)
				(type default)
			)
			(layer "F.Fab")
		)
		(fp_line
			(start 0.12065 -0.3048)
			(end 0.67945 -0.3048)
			(stroke
				(width 0.1)
				(type default)
			)
			(layer "F.Fab")
		)
		(fp_line
			(start 0.12065 -0.2794)
			(end 0.12065 -0.3048)
			(stroke
				(width 0.1)
				(type default)
			)
			(layer "F.Fab")
		)
		(fp_line
			(start -0.12065 -0.2794)
			(end 0.12065 -0.2794)
			(stroke
				(width 0.1)
				(type default)
			)
			(layer "F.Fab")
		)
		(fp_line
			(start 0.120396 0.2794)
			(end -0.12065 0.2794)
			(stroke
				(width 0.1)
				(type default)
			)
			(layer "F.Fab")
		)
		(fp_line
			(start -0.12065 0.2794)
			(end -0.12065 0.3048)
			(stroke
				(width 0.1)
				(type default)
			)
			(layer "F.Fab")
		)
		(fp_line
			(start 0.67945 0.3048)
			(end 0.120396 0.3048)
			(stroke
				(width 0.1)
				(type default)
			)
			(layer "F.Fab")
		)
		(fp_line
			(start 0.120396 0.3048)
			(end 0.120396 0.2794)
			(stroke
				(width 0.1)
				(type default)
			)
			(layer "F.Fab")
		)
		(fp_line
			(start -0.12065 0.3048)
			(end -0.67945 0.3048)
			(stroke
				(width 0.1)
				(type default)
			)
			(layer "F.Fab")
		)
		(fp_line
			(start -0.67945 0.3048)
			(end -0.67945 -0.305054)
			(stroke
				(width 0.1)
				(type default)
			)
			(layer "F.Fab")
		)
		(pad "1" smd rect
			(at -0.40005 0 270)
			(size 0.4572 0.508)
			(layers "F.Cu" "F.Mask" "F.Paste")
			(net "P3V3_AUX")
		)
		(pad "2" smd rect
			(at 0.40005 0 270)
			(size 0.4572 0.508)
			(layers "F.Cu" "F.Mask" "F.Paste")
			(net "FM_BOARD_BMC_SKU_ID2")
		)
	)
	(footprint ""
		(layer "F.Cu")
		(at 215.98128 -41.341548)
		(property "Reference" "C1997"
			(at 0 0 0)
			(layer "F.SilkS")
			(hide yes)
			(effects
				(font
					(size 1.27 1.27)
				)
			)
		)
		(property "Value" ""
			(at 0 0 0)
			(layer "F.Fab")
			(effects
				(font
					(size 1.27 1.27)
				)
			)
		)
		(duplicate_pad_numbers_are_jumpers no)
		(fp_line
			(start -0.7874 -0.4064)
			(end 0.7874 -0.4064)
			(stroke
				(width 0.1524)
				(type default)
			)
			(layer "F.SilkS")
		)
		(fp_line
			(start -0.7874 0.4064)
			(end -0.7874 -0.4064)
			(stroke
				(width 0.1524)
				(type default)
			)
			(layer "F.SilkS")
		)
		(fp_line
			(start 0.7874 -0.4064)
			(end 0.7874 0.4064)
			(stroke
				(width 0.1524)
				(type default)
			)
			(layer "F.SilkS")
		)
		(fp_line
			(start 0.7874 0.4064)
			(end -0.7874 0.4064)
			(stroke
				(width 0.1524)
				(type default)
			)
			(layer "F.SilkS")
		)
		(fp_line
			(start -0.67945 -0.305054)
			(end -0.12065 -0.305054)
			(stroke
				(width 0.1)
				(type default)
			)
			(layer "F.Fab")
		)
		(fp_line
			(start -0.67945 0.3048)
			(end -0.67945 -0.305054)
			(stroke
				(width 0.1)
				(type default)
			)
			(layer "F.Fab")
		)
		(fp_line
			(start -0.12065 -0.305054)
			(end -0.12065 -0.2794)
			(stroke
				(width 0.1)
				(type default)
			)
			(layer "F.Fab")
		)
		(fp_line
			(start -0.12065 -0.2794)
			(end 0.12065 -0.2794)
			(stroke
				(width 0.1)
				(type default)
			)
			(layer "F.Fab")
		)
		(fp_line
			(start -0.12065 0.2794)
			(end -0.12065 0.3048)
			(stroke
				(width 0.1)
				(type default)
			)
			(layer "F.Fab")
		)
		(fp_line
			(start -0.12065 0.3048)
			(end -0.67945 0.3048)
			(stroke
				(width 0.1)
				(type default)
			)
			(layer "F.Fab")
		)
		(fp_line
			(start 0.120396 0.2794)
			(end -0.12065 0.2794)
			(stroke
				(width 0.1)
				(type default)
			)
			(layer "F.Fab")
		)
		(fp_line
			(start 0.120396 0.3048)
			(end 0.120396 0.2794)
			(stroke
				(width 0.1)
				(type default)
			)
			(layer "F.Fab")
		)
		(fp_line
			(start 0.12065 -0.3048)
			(end 0.67945 -0.3048)
			(stroke
				(width 0.1)
				(type default)
			)
			(layer "F.Fab")
		)
		(fp_line
			(start 0.12065 -0.2794)
			(end 0.12065 -0.3048)
			(stroke
				(width 0.1)
				(type default)
			)
			(layer "F.Fab")
		)
		(fp_line
			(start 0.67945 -0.3048)
			(end 0.67945 0.3048)
			(stroke
				(width 0.1)
				(type default)
			)
			(layer "F.Fab")
		)
		(fp_line
			(start 0.67945 0.3048)
			(end 0.120396 0.3048)
			(stroke
				(width 0.1)
				(type default)
			)
			(layer "F.Fab")
		)
		(pad "1" smd circle
			(at -0.40005 0)
			(size 0 0)
			(layers "F.Cu" "F.Mask" "F.Paste")
			(net "P3V3_AUX")
		)
		(pad "2" smd circle
			(at 0.40005 0)
			(size 0 0)
			(layers "F.Cu" "F.Mask" "F.Paste")
			(net "GND")
		)
	)
	(footprint ""
		(layer "F.Cu")
		(at 387.262116 -14.25321 90)
		(property "Reference" "R445"
			(at 0 0 90)
			(layer "F.SilkS")
			(hide yes)
			(effects
				(font
					(size 1.27 1.27)
				)
			)
		)
		(property "Value" ""
			(at 0 0 90)
			(layer "F.Fab")
			(effects
				(font
					(size 1.27 1.27)
				)
			)
		)
		(duplicate_pad_numbers_are_jumpers no)
		(fp_line
			(start 0.7874 -0.4064)
			(end 0.7874 0.4064)
			(stroke
				(width 0.1524)
				(type default)
			)
			(layer "F.SilkS")
		)
		(fp_line
			(start -0.7874 -0.4064)
			(end 0.7874 -0.4064)
			(stroke
				(width 0.1524)
				(type default)
			)
			(layer "F.SilkS")
		)
		(fp_line
			(start 0.7874 0.4064)
			(end -0.7874 0.4064)
			(stroke
				(width 0.1524)
				(type default)
			)
			(layer "F.SilkS")
		)
		(fp_line
			(start -0.7874 0.4064)
			(end -0.7874 -0.4064)
			(stroke
				(width 0.1524)
				(type default)
			)
			(layer "F.SilkS")
		)
		(fp_line
			(start -0.12065 -0.305054)
			(end -0.12065 -0.2794)
			(stroke
				(width 0.1)
				(type default)
			)
			(layer "F.Fab")
		)
		(fp_line
			(start -0.67945 -0.305054)
			(end -0.12065 -0.305054)
			(stroke
				(width 0.1)
				(type default)
			)
			(layer "F.Fab")
		)
		(fp_line
			(start 0.67945 -0.3048)
			(end 0.67945 0.3048)
			(stroke
				(width 0.1)
				(type default)
			)
			(layer "F.Fab")
		)
		(fp_line
			(start 0.12065 -0.3048)
			(end 0.67945 -0.3048)
			(stroke
				(width 0.1)
				(type default)
			)
			(layer "F.Fab")
		)
		(fp_line
			(start 0.12065 -0.2794)
			(end 0.12065 -0.3048)
			(stroke
				(width 0.1)
				(type default)
			)
			(layer "F.Fab")
		)
		(fp_line
			(start -0.12065 -0.2794)
			(end 0.12065 -0.2794)
			(stroke
				(width 0.1)
				(type default)
			)
			(layer "F.Fab")
		)
		(fp_line
			(start 0.120396 0.2794)
			(end -0.12065 0.2794)
			(stroke
				(width 0.1)
				(type default)
			)
			(layer "F.Fab")
		)
		(fp_line
			(start -0.12065 0.2794)
			(end -0.12065 0.3048)
			(stroke
				(width 0.1)
				(type default)
			)
			(layer "F.Fab")
		)
		(fp_line
			(start 0.67945 0.3048)
			(end 0.120396 0.3048)
			(stroke
				(width 0.1)
				(type default)
			)
			(layer "F.Fab")
		)
		(fp_line
			(start 0.120396 0.3048)
			(end 0.120396 0.2794)
			(stroke
				(width 0.1)
				(type default)
			)
			(layer "F.Fab")
		)
		(fp_line
			(start -0.12065 0.3048)
			(end -0.67945 0.3048)
			(stroke
				(width 0.1)
				(type default)
			)
			(layer "F.Fab")
		)
		(fp_line
			(start -0.67945 0.3048)
			(end -0.67945 -0.305054)
			(stroke
				(width 0.1)
				(type default)
			)
			(layer "F.Fab")
		)
		(pad "1" smd circle
			(at -0.40005 0 90)
			(size 0 0)
			(layers "F.Cu" "F.Mask" "F.Paste")
			(net "OCP_SFF_USB2_3_DP")
		)
		(pad "2" smd circle
			(at 0.40005 0 90)
			(size 0 0)
			(layers "F.Cu" "F.Mask" "F.Paste")
			(net "USB2_3_DP")
		)
	)
	(footprint ""
		(layer "F.Cu")
		(at 424.223942 -396.635478)
		(property "Reference" "R3464"
			(at 0 0 0)
			(layer "F.SilkS")
			(hide yes)
			(effects
				(font
					(size 1.27 1.27)
				)
			)
		)
		(property "Value" ""
			(at 0 0 0)
			(layer "F.Fab")
			(effects
				(font
					(size 1.27 1.27)
				)
			)
		)
		(duplicate_pad_numbers_are_jumpers no)
		(fp_line
			(start -0.7874 -0.4064)
			(end 0.7874 -0.4064)
			(stroke
				(width 0.1524)
				(type default)
			)
			(layer "F.SilkS")
		)
		(fp_line
			(start -0.7874 0.4064)
			(end -0.7874 -0.4064)
			(stroke
				(width 0.1524)
				(type default)
			)
			(layer "F.SilkS")
		)
		(fp_line
			(start 0.7874 -0.4064)
			(end 0.7874 0.4064)
			(stroke
				(width 0.1524)
				(type default)
			)
			(layer "F.SilkS")
		)
		(fp_line
			(start 0.7874 0.4064)
			(end -0.7874 0.4064)
			(stroke
				(width 0.1524)
				(type default)
			)
			(layer "F.SilkS")
		)
		(fp_line
			(start -0.67945 -0.305054)
			(end -0.12065 -0.305054)
			(stroke
				(width 0.1)
				(type default)
			)
			(layer "F.Fab")
		)
		(fp_line
			(start -0.67945 0.3048)
			(end -0.67945 -0.305054)
			(stroke
				(width 0.1)
				(type default)
			)
			(layer "F.Fab")
		)
		(fp_line
			(start -0.12065 -0.305054)
			(end -0.12065 -0.2794)
			(stroke
				(width 0.1)
				(type default)
			)
			(layer "F.Fab")
		)
		(fp_line
			(start -0.12065 -0.2794)
			(end 0.12065 -0.2794)
			(stroke
				(width 0.1)
				(type default)
			)
			(layer "F.Fab")
		)
		(fp_line
			(start -0.12065 0.2794)
			(end -0.12065 0.3048)
			(stroke
				(width 0.1)
				(type default)
			)
			(layer "F.Fab")
		)
		(fp_line
			(start -0.12065 0.3048)
			(end -0.67945 0.3048)
			(stroke
				(width 0.1)
				(type default)
			)
			(layer "F.Fab")
		)
		(fp_line
			(start 0.120396 0.2794)
			(end -0.12065 0.2794)
			(stroke
				(width 0.1)
				(type default)
			)
			(layer "F.Fab")
		)
		(fp_line
			(start 0.120396 0.3048)
			(end 0.120396 0.2794)
			(stroke
				(width 0.1)
				(type default)
			)
			(layer "F.Fab")
		)
		(fp_line
			(start 0.12065 -0.3048)
			(end 0.67945 -0.3048)
			(stroke
				(width 0.1)
				(type default)
			)
			(layer "F.Fab")
		)
		(fp_line
			(start 0.12065 -0.2794)
			(end 0.12065 -0.3048)
			(stroke
				(width 0.1)
				(type default)
			)
			(layer "F.Fab")
		)
		(fp_line
			(start 0.67945 -0.3048)
			(end 0.67945 0.3048)
			(stroke
				(width 0.1)
				(type default)
			)
			(layer "F.Fab")
		)
		(fp_line
			(start 0.67945 0.3048)
			(end 0.120396 0.3048)
			(stroke
				(width 0.1)
				(type default)
			)
			(layer "F.Fab")
		)
		(pad "1" smd circle
			(at -0.40005 0)
			(size 0 0)
			(layers "F.Cu" "F.Mask" "F.Paste")
			(net "P3V3_AUX")
		)
		(pad "2" smd circle
			(at 0.40005 0)
			(size 0 0)
			(layers "F.Cu" "F.Mask" "F.Paste")
			(net "GPU_FPGA_OVERT_N")
		)
	)
)
